(kicad_pcb
	(version 20260206)
	(generator "pcbnew")
	(generator_version "10.0")
	(general
		(thickness 1.6)
		(legacy_teardrops no)
	)
	(paper "A4")
	(title_block
		(title "03242023_DA0F0TMBIJ0_F0T_Motherboard_J_brd_V01_OCP.brd")
		(comment 1 "Grand Teton / footprints 4859-4864 of 6105")
	)
	(layers
		(0 "F.Cu" signal "TOP")
		(4 "In1.Cu" signal "GND")
		(6 "In2.Cu" signal "IN1")
		(8 "In3.Cu" signal "GND1")
		(10 "In4.Cu" signal "IN2")
		(12 "In5.Cu" signal "GND2")
		(14 "In6.Cu" signal "IN3")
		(16 "In7.Cu" signal "GND3")
		(18 "In8.Cu" signal "VCC")
		(20 "In9.Cu" signal "VCC1")
		(22 "In10.Cu" signal "GND4")
		(24 "In11.Cu" signal "IN4")
		(26 "In12.Cu" signal "GND5")
		(28 "In13.Cu" signal "IN5")
		(30 "In14.Cu" signal "GND6")
		(32 "In15.Cu" signal "IN6")
		(34 "In16.Cu" signal "GND7")
		(2 "B.Cu" signal "BOTTOM")
		(9 "F.Adhes" user "F.Adhesive")
		(11 "B.Adhes" user "B.Adhesive")
		(13 "F.Paste" user "Package Geometry/Pastemask Top")
		(15 "B.Paste" user "Package Geometry/Pastemask Bottom")
		(5 "F.SilkS" user "Ref Des/Silkscreen Top")
		(7 "B.SilkS" user "Ref Des/Silkscreen Bottom")
		(1 "F.Mask" user "Board Geometry/Soldermask Top")
		(3 "B.Mask" user "Board Geometry/Soldermask Bottom")
		(17 "Dwgs.User" user "User.Drawings")
		(19 "Cmts.User" user "User.Comments")
		(21 "Eco1.User" user "User.Eco1")
		(23 "Eco2.User" user "User.Eco2")
		(25 "Edge.Cuts" user "Board Geometry/Outline")
		(27 "Margin" user)
		(31 "F.CrtYd" user "Package Geometry/Place Bound Top")
		(29 "B.CrtYd" user "Package Geometry/Place Bound Bottom")
		(35 "F.Fab" user "Ref Des/Assembly Top")
		(33 "B.Fab" user "Ref Des/Assembly Bottom")
	)
	(footprint ""
		(layer "B.Cu")
		(at 36.968938 -126.40056)
		(property "Reference" "R4781"
			(at 0 0 0)
			(layer "B.SilkS")
			(hide yes)
			(effects
				(font
					(size 1.27 1.27)
				)
				(justify mirror)
			)
		)
		(property "Value" ""
			(at 0 0 0)
			(layer "B.Fab")
			(effects
				(font
					(size 1.27 1.27)
				)
				(justify mirror)
			)
		)
		(duplicate_pad_numbers_are_jumpers no)
		(fp_line
			(start -0.7874 -0.4064)
			(end -0.7874 0.4064)
			(stroke
				(width 0.1524)
				(type default)
			)
			(layer "B.SilkS")
		)
		(fp_line
			(start -0.7874 0.4064)
			(end 0.7874 0.4064)
			(stroke
				(width 0.1524)
				(type default)
			)
			(layer "B.SilkS")
		)
		(fp_line
			(start 0.7874 -0.4064)
			(end -0.7874 -0.4064)
			(stroke
				(width 0.1524)
				(type default)
			)
			(layer "B.SilkS")
		)
		(fp_line
			(start 0.7874 0.4064)
			(end 0.7874 -0.4064)
			(stroke
				(width 0.1524)
				(type default)
			)
			(layer "B.SilkS")
		)
		(fp_line
			(start -0.67945 -0.3048)
			(end -0.67945 0.3048)
			(stroke
				(width 0.1)
				(type default)
			)
			(layer "B.Fab")
		)
		(fp_line
			(start -0.67945 0.3048)
			(end -0.120396 0.3048)
			(stroke
				(width 0.1)
				(type default)
			)
			(layer "B.Fab")
		)
		(fp_line
			(start -0.12065 -0.3048)
			(end -0.67945 -0.3048)
			(stroke
				(width 0.1)
				(type default)
			)
			(layer "B.Fab")
		)
		(fp_line
			(start -0.12065 -0.2794)
			(end -0.12065 -0.3048)
			(stroke
				(width 0.1)
				(type default)
			)
			(layer "B.Fab")
		)
		(fp_line
			(start -0.120396 0.2794)
			(end 0.12065 0.2794)
			(stroke
				(width 0.1)
				(type default)
			)
			(layer "B.Fab")
		)
		(fp_line
			(start -0.120396 0.3048)
			(end -0.120396 0.2794)
			(stroke
				(width 0.1)
				(type default)
			)
			(layer "B.Fab")
		)
		(fp_line
			(start 0.12065 -0.305054)
			(end 0.12065 -0.2794)
			(stroke
				(width 0.1)
				(type default)
			)
			(layer "B.Fab")
		)
		(fp_line
			(start 0.12065 -0.2794)
			(end -0.12065 -0.2794)
			(stroke
				(width 0.1)
				(type default)
			)
			(layer "B.Fab")
		)
		(fp_line
			(start 0.12065 0.2794)
			(end 0.12065 0.3048)
			(stroke
				(width 0.1)
				(type default)
			)
			(layer "B.Fab")
		)
		(fp_line
			(start 0.12065 0.3048)
			(end 0.67945 0.3048)
			(stroke
				(width 0.1)
				(type default)
			)
			(layer "B.Fab")
		)
		(fp_line
			(start 0.67945 -0.305054)
			(end 0.12065 -0.305054)
			(stroke
				(width 0.1)
				(type default)
			)
			(layer "B.Fab")
		)
		(fp_line
			(start 0.67945 0.3048)
			(end 0.67945 -0.305054)
			(stroke
				(width 0.1)
				(type default)
			)
			(layer "B.Fab")
		)
		(pad "1" smd circle
			(at 0.40005 0 180)
			(size 0 0)
			(layers "B.Cu" "B.Mask" "B.Paste")
			(net "PWRGD_PVCCINFAON_CPU1")
		)
		(pad "2" smd circle
			(at -0.40005 0 180)
			(size 0 0)
			(layers "B.Cu" "B.Mask" "B.Paste")
			(net "PWRGD_PVCCINFAON_CPU1_R")
		)
	)
	(footprint ""
		(layer "B.Cu")
		(at 117.87632 -237.709456 -90)
		(property "Reference" "C489"
			(at 0 0 90)
			(layer "B.SilkS")
			(hide yes)
			(effects
				(font
					(size 1.27 1.27)
				)
				(justify mirror)
			)
		)
		(property "Value" ""
			(at 0 0 90)
			(layer "B.Fab")
			(effects
				(font
					(size 1.27 1.27)
				)
				(justify mirror)
			)
		)
		(duplicate_pad_numbers_are_jumpers no)
		(fp_line
			(start -1.2954 0.5842)
			(end 1.2954 0.5842)
			(stroke
				(width 0.1524)
				(type default)
			)
			(layer "B.SilkS")
		)
		(fp_line
			(start 1.2954 0.5842)
			(end 1.2954 -0.5842)
			(stroke
				(width 0.1524)
				(type default)
			)
			(layer "B.SilkS")
		)
		(fp_line
			(start -1.2954 -0.5842)
			(end -1.2954 0.5842)
			(stroke
				(width 0.1524)
				(type default)
			)
			(layer "B.SilkS")
		)
		(fp_line
			(start 0 -0.5842)
			(end 0 0.5842)
			(stroke
				(width 0.1524)
				(type default)
			)
			(layer "B.SilkS")
		)
		(fp_line
			(start 1.2954 -0.5842)
			(end -1.2954 -0.5842)
			(stroke
				(width 0.1524)
				(type default)
			)
			(layer "B.SilkS")
		)
		(fp_line
			(start -0.8636 0.4572)
			(end 0.8636 0.4572)
			(stroke
				(width 0.1)
				(type default)
			)
			(layer "B.Fab")
		)
		(fp_line
			(start 0.8636 0.4572)
			(end 0.8636 0.4064)
			(stroke
				(width 0.1)
				(type default)
			)
			(layer "B.Fab")
		)
		(fp_line
			(start -1.1938 0.4064)
			(end -0.8636 0.4064)
			(stroke
				(width 0.1)
				(type default)
			)
			(layer "B.Fab")
		)
		(fp_line
			(start -0.8636 0.4064)
			(end -0.8636 0.4572)
			(stroke
				(width 0.1)
				(type default)
			)
			(layer "B.Fab")
		)
		(fp_line
			(start 0.8636 0.4064)
			(end 1.1938 0.4064)
			(stroke
				(width 0.1)
				(type default)
			)
			(layer "B.Fab")
		)
		(fp_line
			(start 1.1938 0.4064)
			(end 1.1938 -0.4064)
			(stroke
				(width 0.1)
				(type default)
			)
			(layer "B.Fab")
		)
		(fp_line
			(start -1.1938 -0.4064)
			(end -1.1938 0.4064)
			(stroke
				(width 0.1)
				(type default)
			)
			(layer "B.Fab")
		)
		(fp_line
			(start -0.8636 -0.4064)
			(end -1.1938 -0.4064)
			(stroke
				(width 0.1)
				(type default)
			)
			(layer "B.Fab")
		)
		(fp_line
			(start 0.8636 -0.4064)
			(end 0.8636 -0.4572)
			(stroke
				(width 0.1)
				(type default)
			)
			(layer "B.Fab")
		)
		(fp_line
			(start 1.1938 -0.4064)
			(end 0.8636 -0.4064)
			(stroke
				(width 0.1)
				(type default)
			)
			(layer "B.Fab")
		)
		(fp_line
			(start -0.8636 -0.4572)
			(end -0.8636 -0.4064)
			(stroke
				(width 0.1)
				(type default)
			)
			(layer "B.Fab")
		)
		(fp_line
			(start 0.8636 -0.4572)
			(end -0.8636 -0.4572)
			(stroke
				(width 0.1)
				(type default)
			)
			(layer "B.Fab")
		)
		(pad "1" smd rect
			(at 0.7366 0 180)
			(size 0.7112 0.8128)
			(layers "B.Cu" "B.Mask" "B.Paste")
			(net "PVCCINFAON_CPU1")
		)
		(pad "2" smd rect
			(at -0.7366 0 180)
			(size 0.7112 0.8128)
			(layers "B.Cu" "B.Mask" "B.Paste")
			(net "GND")
		)
	)
	(footprint ""
		(layer "B.Cu")
		(at 114.369596 -357.436166)
		(property "Reference" "PR306"
			(at 0 0 0)
			(layer "B.SilkS")
			(hide yes)
			(effects
				(font
					(size 1.27 1.27)
				)
				(justify mirror)
			)
		)
		(property "Value" ""
			(at 0 0 0)
			(layer "B.Fab")
			(effects
				(font
					(size 1.27 1.27)
				)
				(justify mirror)
			)
		)
		(duplicate_pad_numbers_are_jumpers no)
		(fp_line
			(start -0.7874 -0.4064)
			(end -0.7874 0.4064)
			(stroke
				(width 0.1524)
				(type default)
			)
			(layer "B.SilkS")
		)
		(fp_line
			(start -0.7874 0.4064)
			(end 0.7874 0.4064)
			(stroke
				(width 0.1524)
				(type default)
			)
			(layer "B.SilkS")
		)
		(fp_line
			(start 0.7874 -0.4064)
			(end -0.7874 -0.4064)
			(stroke
				(width 0.1524)
				(type default)
			)
			(layer "B.SilkS")
		)
		(fp_line
			(start 0.7874 0.4064)
			(end 0.7874 -0.4064)
			(stroke
				(width 0.1524)
				(type default)
			)
			(layer "B.SilkS")
		)
		(fp_line
			(start -0.67945 -0.3048)
			(end -0.67945 0.3048)
			(stroke
				(width 0.1)
				(type default)
			)
			(layer "B.Fab")
		)
		(fp_line
			(start -0.67945 0.3048)
			(end -0.120396 0.3048)
			(stroke
				(width 0.1)
				(type default)
			)
			(layer "B.Fab")
		)
		(fp_line
			(start -0.12065 -0.3048)
			(end -0.67945 -0.3048)
			(stroke
				(width 0.1)
				(type default)
			)
			(layer "B.Fab")
		)
		(fp_line
			(start -0.12065 -0.2794)
			(end -0.12065 -0.3048)
			(stroke
				(width 0.1)
				(type default)
			)
			(layer "B.Fab")
		)
		(fp_line
			(start -0.120396 0.2794)
			(end 0.12065 0.2794)
			(stroke
				(width 0.1)
				(type default)
			)
			(layer "B.Fab")
		)
		(fp_line
			(start -0.120396 0.3048)
			(end -0.120396 0.2794)
			(stroke
				(width 0.1)
				(type default)
			)
			(layer "B.Fab")
		)
		(fp_line
			(start 0.12065 -0.305054)
			(end 0.12065 -0.2794)
			(stroke
				(width 0.1)
				(type default)
			)
			(layer "B.Fab")
		)
		(fp_line
			(start 0.12065 -0.2794)
			(end -0.12065 -0.2794)
			(stroke
				(width 0.1)
				(type default)
			)
			(layer "B.Fab")
		)
		(fp_line
			(start 0.12065 0.2794)
			(end 0.12065 0.3048)
			(stroke
				(width 0.1)
				(type default)
			)
			(layer "B.Fab")
		)
		(fp_line
			(start 0.12065 0.3048)
			(end 0.67945 0.3048)
			(stroke
				(width 0.1)
				(type default)
			)
			(layer "B.Fab")
		)
		(fp_line
			(start 0.67945 -0.305054)
			(end 0.12065 -0.305054)
			(stroke
				(width 0.1)
				(type default)
			)
			(layer "B.Fab")
		)
		(fp_line
			(start 0.67945 0.3048)
			(end 0.67945 -0.305054)
			(stroke
				(width 0.1)
				(type default)
			)
			(layer "B.Fab")
		)
		(pad "1" smd circle
			(at 0.40005 0 180)
			(size 0 0)
			(layers "B.Cu" "B.Mask" "B.Paste")
			(net "PVCCIN_CPU1_VREF")
		)
		(pad "2" smd circle
			(at -0.40005 0 180)
			(size 0 0)
			(layers "B.Cu" "B.Mask" "B.Paste")
			(net "PVCCIN_CPU1_ADDR")
		)
	)
	(footprint ""
		(layer "B.Cu")
		(at 459.572614 -321.549776 -90)
		(property "Reference" "C45"
			(at 0 0 90)
			(layer "B.SilkS")
			(hide yes)
			(effects
				(font
					(size 1.27 1.27)
				)
				(justify mirror)
			)
		)
		(property "Value" ""
			(at 0 0 90)
			(layer "B.Fab")
			(effects
				(font
					(size 1.27 1.27)
				)
				(justify mirror)
			)
		)
		(duplicate_pad_numbers_are_jumpers no)
		(fp_line
			(start -1.524 0.762)
			(end 1.524 0.762)
			(stroke
				(width 0.1524)
				(type default)
			)
			(layer "B.SilkS")
		)
		(fp_line
			(start 1.524 0.762)
			(end 1.524 -0.762)
			(stroke
				(width 0.1524)
				(type default)
			)
			(layer "B.SilkS")
		)
		(fp_line
			(start -1.524 -0.762)
			(end -1.524 0.762)
			(stroke
				(width 0.1524)
				(type default)
			)
			(layer "B.SilkS")
		)
		(fp_line
			(start 1.524 -0.762)
			(end -1.524 -0.762)
			(stroke
				(width 0.1524)
				(type default)
			)
			(layer "B.SilkS")
		)
		(fp_line
			(start -1.1049 0.724916)
			(end -1.1049 -0.724916)
			(stroke
				(width 0.1)
				(type default)
			)
			(layer "B.Fab")
		)
		(fp_line
			(start 1.1049 0.724916)
			(end -1.1049 0.724916)
			(stroke
				(width 0.1)
				(type default)
			)
			(layer "B.Fab")
		)
		(fp_line
			(start -1.1049 -0.724916)
			(end 1.1049 -0.724916)
			(stroke
				(width 0.1)
				(type default)
			)
			(layer "B.Fab")
		)
		(fp_line
			(start 1.1049 -0.724916)
			(end 1.1049 0.724916)
			(stroke
				(width 0.1)
				(type default)
			)
			(layer "B.Fab")
		)
		(pad "1" smd rect
			(at 0.889 0 270)
			(size 1.016 1.27)
			(layers "B.Cu" "B.Mask" "B.Paste")
			(net "P12V_S3_AUX_CPU0_NVDIMM")
		)
		(pad "2" smd rect
			(at -0.889 0 270)
			(size 1.016 1.27)
			(layers "B.Cu" "B.Mask" "B.Paste")
			(net "GND")
		)
	)
	(footprint ""
		(layer "B.Cu")
		(at 303.149254 -319.05956)
		(property "Reference" "R26"
			(at 0 0 0)
			(layer "B.SilkS")
			(hide yes)
			(effects
				(font
					(size 1.27 1.27)
				)
				(justify mirror)
			)
		)
		(property "Value" ""
			(at 0 0 0)
			(layer "B.Fab")
			(effects
				(font
					(size 1.27 1.27)
				)
				(justify mirror)
			)
		)
		(duplicate_pad_numbers_are_jumpers no)
		(fp_line
			(start -0.7874 -0.4064)
			(end -0.7874 0.4064)
			(stroke
				(width 0.1524)
				(type default)
			)
			(layer "B.SilkS")
		)
		(fp_line
			(start -0.7874 0.4064)
			(end 0.7874 0.4064)
			(stroke
				(width 0.1524)
				(type default)
			)
			(layer "B.SilkS")
		)
		(fp_line
			(start 0.7874 -0.4064)
			(end -0.7874 -0.4064)
			(stroke
				(width 0.1524)
				(type default)
			)
			(layer "B.SilkS")
		)
		(fp_line
			(start 0.7874 0.4064)
			(end 0.7874 -0.4064)
			(stroke
				(width 0.1524)
				(type default)
			)
			(layer "B.SilkS")
		)
		(fp_line
			(start -0.67945 -0.3048)
			(end -0.67945 0.3048)
			(stroke
				(width 0.1)
				(type default)
			)
			(layer "B.Fab")
		)
		(fp_line
			(start -0.67945 0.3048)
			(end -0.120396 0.3048)
			(stroke
				(width 0.1)
				(type default)
			)
			(layer "B.Fab")
		)
		(fp_line
			(start -0.12065 -0.3048)
			(end -0.67945 -0.3048)
			(stroke
				(width 0.1)
				(type default)
			)
			(layer "B.Fab")
		)
		(fp_line
			(start -0.12065 -0.2794)
			(end -0.12065 -0.3048)
			(stroke
				(width 0.1)
				(type default)
			)
			(layer "B.Fab")
		)
		(fp_line
			(start -0.120396 0.2794)
			(end 0.12065 0.2794)
			(stroke
				(width 0.1)
				(type default)
			)
			(layer "B.Fab")
		)
		(fp_line
			(start -0.120396 0.3048)
			(end -0.120396 0.2794)
			(stroke
				(width 0.1)
				(type default)
			)
			(layer "B.Fab")
		)
		(fp_line
			(start 0.12065 -0.305054)
			(end 0.12065 -0.2794)
			(stroke
				(width 0.1)
				(type default)
			)
			(layer "B.Fab")
		)
		(fp_line
			(start 0.12065 -0.2794)
			(end -0.12065 -0.2794)
			(stroke
				(width 0.1)
				(type default)
			)
			(layer "B.Fab")
		)
		(fp_line
			(start 0.12065 0.2794)
			(end 0.12065 0.3048)
			(stroke
				(width 0.1)
				(type default)
			)
			(layer "B.Fab")
		)
		(fp_line
			(start 0.12065 0.3048)
			(end 0.67945 0.3048)
			(stroke
				(width 0.1)
				(type default)
			)
			(layer "B.Fab")
		)
		(fp_line
			(start 0.67945 -0.305054)
			(end 0.12065 -0.305054)
			(stroke
				(width 0.1)
				(type default)
			)
			(layer "B.Fab")
		)
		(fp_line
			(start 0.67945 0.3048)
			(end 0.67945 -0.305054)
			(stroke
				(width 0.1)
				(type default)
			)
			(layer "B.Fab")
		)
		(pad "1" smd circle
			(at 0.40005 0 180)
			(size 0 0)
			(layers "B.Cu" "B.Mask" "B.Paste")
			(net "PD_CHA_CPU0_DIMM1_SAA")
		)
		(pad "2" smd circle
			(at -0.40005 0 180)
			(size 0 0)
			(layers "B.Cu" "B.Mask" "B.Paste")
			(net "GND")
		)
	)
	(footprint ""
		(layer "B.Cu")
		(at 16.610838 -97.314512 90)
		(property "Reference" "C2039"
			(at 0 0 90)
			(layer "B.SilkS")
			(hide yes)
			(effects
				(font
					(size 1.27 1.27)
				)
				(justify mirror)
			)
		)
		(property "Value" ""
			(at 0 0 90)
			(layer "B.Fab")
			(effects
				(font
					(size 1.27 1.27)
				)
				(justify mirror)
			)
		)
		(duplicate_pad_numbers_are_jumpers no)
		(fp_line
			(start 0.7874 -0.4064)
			(end -0.7874 -0.4064)
			(stroke
				(width 0.1524)
				(type default)
			)
			(layer "B.SilkS")
		)
		(fp_line
			(start -0.7874 -0.4064)
			(end -0.7874 0.4064)
			(stroke
				(width 0.1524)
				(type default)
			)
			(layer "B.SilkS")
		)
		(fp_line
			(start 0.7874 0.4064)
			(end 0.7874 -0.4064)
			(stroke
				(width 0.1524)
				(type default)
			)
			(layer "B.SilkS")
		)
		(fp_line
			(start -0.7874 0.4064)
			(end 0.7874 0.4064)
			(stroke
				(width 0.1524)
				(type default)
			)
			(layer "B.SilkS")
		)
		(fp_line
			(start 0.67945 -0.305054)
			(end 0.12065 -0.305054)
			(stroke
				(width 0.1)
				(type default)
			)
			(layer "B.Fab")
		)
		(fp_line
			(start 0.12065 -0.305054)
			(end 0.12065 -0.2794)
			(stroke
				(width 0.1)
				(type default)
			)
			(layer "B.Fab")
		)
		(fp_line
			(start -0.12065 -0.3048)
			(end -0.67945 -0.3048)
			(stroke
				(width 0.1)
				(type default)
			)
			(layer "B.Fab")
		)
		(fp_line
			(start -0.67945 -0.3048)
			(end -0.67945 0.3048)
			(stroke
				(width 0.1)
				(type default)
			)
			(layer "B.Fab")
		)
		(fp_line
			(start 0.12065 -0.2794)
			(end -0.12065 -0.2794)
			(stroke
				(width 0.1)
				(type default)
			)
			(layer "B.Fab")
		)
		(fp_line
			(start -0.12065 -0.2794)
			(end -0.12065 -0.3048)
			(stroke
				(width 0.1)
				(type default)
			)
			(layer "B.Fab")
		)
		(fp_line
			(start 0.12065 0.2794)
			(end 0.12065 0.3048)
			(stroke
				(width 0.1)
				(type default)
			)
			(layer "B.Fab")
		)
		(fp_line
			(start -0.120396 0.2794)
			(end 0.12065 0.2794)
			(stroke
				(width 0.1)
				(type default)
			)
			(layer "B.Fab")
		)
		(fp_line
			(start 0.67945 0.3048)
			(end 0.67945 -0.305054)
			(stroke
				(width 0.1)
				(type default)
			)
			(layer "B.Fab")
		)
		(fp_line
			(start 0.12065 0.3048)
			(end 0.67945 0.3048)
			(stroke
				(width 0.1)
				(type default)
			)
			(layer "B.Fab")
		)
		(fp_line
			(start -0.120396 0.3048)
			(end -0.120396 0.2794)
			(stroke
				(width 0.1)
				(type default)
			)
			(layer "B.Fab")
		)
		(fp_line
			(start -0.67945 0.3048)
			(end -0.120396 0.3048)
			(stroke
				(width 0.1)
				(type default)
			)
			(layer "B.Fab")
		)
		(pad "1" smd circle
			(at 0.40005 0 270)
			(size 0 0)
			(layers "B.Cu" "B.Mask" "B.Paste")
			(net "P3V3_AUX_USB_HUB")
		)
		(pad "2" smd circle
			(at -0.40005 0 270)
			(size 0 0)
			(layers "B.Cu" "B.Mask" "B.Paste")
			(net "GND")
		)
	)
)
